(kicad_pcb
	(version 20260206)
	(generator "pcbnew")
	(generator_version "10.0")
	(general
		(thickness 1.6)
		(legacy_teardrops no)
	)
	(paper "A4")
	(title_block
		(title "Wiwynn_Tioga_Pass_MB.brd")
		(comment 1 "Tioga Pass / footprints 4488-4495 of 4770")
	)
	(layers
		(0 "F.Cu" signal "TOP")
		(4 "In1.Cu" signal "L2GND")
		(6 "In2.Cu" signal "L3")
		(8 "In3.Cu" signal "L4GND")
		(10 "In4.Cu" signal "L5")
		(12 "In5.Cu" signal "L6GND")
		(14 "In6.Cu" signal "L7VCC")
		(16 "In7.Cu" signal "L8VCC")
		(18 "In8.Cu" signal "L9GND")
		(20 "In9.Cu" signal "L10")
		(22 "In10.Cu" signal "L11GND")
		(24 "In11.Cu" signal "L12")
		(26 "In12.Cu" signal "L13GND")
		(2 "B.Cu" signal "BOTTOM")
		(9 "F.Adhes" user "F.Adhesive")
		(11 "B.Adhes" user "B.Adhesive")
		(13 "F.Paste" user "Package Geometry/Pastemask Top")
		(15 "B.Paste" user "Package Geometry/Pastemask Bottom")
		(5 "F.SilkS" user "Ref Des/Silkscreen Top")
		(7 "B.SilkS" user "Ref Des/Silkscreen Bottom")
		(1 "F.Mask" user "Board Geometry/Soldermask Top")
		(3 "B.Mask" user "Board Geometry/Soldermask Bottom")
		(17 "Dwgs.User" user "User.Drawings")
		(19 "Cmts.User" user "User.Comments")
		(21 "Eco1.User" user "User.Eco1")
		(23 "Eco2.User" user "User.Eco2")
		(25 "Edge.Cuts" user "Board Geometry/Outline")
		(27 "Margin" user)
		(31 "F.CrtYd" user "Package Geometry/Place Bound Top")
		(29 "B.CrtYd" user "Package Geometry/Place Bound Bottom")
		(35 "F.Fab" user "Ref Des/Assembly Top")
		(33 "B.Fab" user "Ref Des/Assembly Bottom")
	)
	(footprint ""
		(layer "B.Cu")
		(at 373.126 -75.5015)
		(property "Reference" "C3R2"
			(at 0 0 0)
			(layer "B.SilkS")
			(hide yes)
			(effects
				(font
					(size 1.27 1.27)
				)
				(justify mirror)
			)
		)
		(property "Value" ""
			(at 0 0 0)
			(layer "B.Fab")
			(effects
				(font
					(size 1.27 1.27)
				)
				(justify mirror)
			)
		)
		(duplicate_pad_numbers_are_jumpers no)
		(fp_rect
			(start 0.2794 0.9144)
			(end -0.2794 -0.1143)
			(stroke
				(width 0)
				(type default)
			)
			(fill no)
			(layer "B.CrtYd")
		)
		(fp_line
			(start -0.2794 -0.1143)
			(end -0.2794 0.9144)
			(stroke
				(width 0.1)
				(type default)
			)
			(layer "B.Fab")
		)
		(fp_line
			(start -0.2794 0.9144)
			(end 0.2794 0.9144)
			(stroke
				(width 0.1)
				(type default)
			)
			(layer "B.Fab")
		)
		(fp_line
			(start 0.2794 -0.1143)
			(end -0.2794 -0.1143)
			(stroke
				(width 0.1)
				(type default)
			)
			(layer "B.Fab")
		)
		(fp_line
			(start 0.2794 0.9144)
			(end 0.2794 -0.1143)
			(stroke
				(width 0.1)
				(type default)
			)
			(layer "B.Fab")
		)
		(pad "1" smd custom
			(at 0 0 270)
			(size 0.10414 0.10414)
			(layers "B.Cu" "B.Mask" "B.Paste")
			(net "P3V3_STBY")
			(options
				(clearance outline)
				(anchor circle)
			)
			(primitives
				(gr_poly
					(pts
						(xy -0.20828 -0.08636) (xy -0.20828 0.08636) (xy -0.08636 0.20828) (xy 0.086614 0.20828) (xy 0.20828 0.086614)
						(xy 0.20828 -0.08636) (xy 0.08636 -0.20828) (xy -0.08636 -0.20828)
					)
					(width 0)
					(fill yes)
				)
			)
		)
		(pad "2" smd custom
			(at 0 0.8001 270)
			(size 0.10414 0.10414)
			(layers "B.Cu" "B.Mask" "B.Paste")
			(net "GND")
			(options
				(clearance outline)
				(anchor circle)
			)
			(primitives
				(gr_poly
					(pts
						(xy -0.20828 -0.08636) (xy -0.20828 0.08636) (xy -0.08636 0.20828) (xy 0.086614 0.20828) (xy 0.20828 0.086614)
						(xy 0.20828 -0.08636) (xy 0.08636 -0.20828) (xy -0.08636 -0.20828)
					)
					(width 0)
					(fill yes)
				)
			)
		)
		(zone
			(layer "B.Cu")
			(hatch none 0.5)
			(connect_pads
				(clearance 0)
			)
			(min_thickness 0.25)
			(keepout
				(tracks not_allowed)
				(vias allowed)
				(pads allowed)
				(copperpour not_allowed)
				(footprints allowed)
			)
			(placement
				(enabled no)
				(sheetname "")
			)
			(fill
				(thermal_gap 0.5)
				(thermal_bridge_width 0.5)
				(island_removal_mode 0)
			)
			(polygon
				(pts
					(xy 373.21363 -75.29195) (xy 373.21363 -74.91095) (xy 373.03837 -74.91095) (xy 373.038116 -75.29195)
				)
			)
		)
		(zone
			(layer "B.Cu")
			(hatch none 0.5)
			(connect_pads
				(clearance 0)
			)
			(min_thickness 0.25)
			(keepout
				(tracks allowed)
				(vias not_allowed)
				(pads allowed)
				(copperpour not_allowed)
				(footprints allowed)
			)
			(placement
				(enabled no)
				(sheetname "")
			)
			(fill
				(thermal_gap 0.5)
				(thermal_bridge_width 0.5)
				(island_removal_mode 0)
			)
			(polygon
				(pts
					(xy 373.21363 -75.29195) (xy 373.21363 -74.91095) (xy 373.03837 -74.91095) (xy 373.038116 -75.29195)
				)
			)
		)
	)
	(footprint ""
		(layer "B.Cu")
		(at 32.832802 -97.286064 90)
		(property "Reference" "C9N13"
			(at 0 0 90)
			(layer "B.SilkS")
			(hide yes)
			(effects
				(font
					(size 1.27 1.27)
				)
				(justify mirror)
			)
		)
		(property "Value" ""
			(at 0 0 90)
			(layer "B.Fab")
			(effects
				(font
					(size 1.27 1.27)
				)
				(justify mirror)
			)
		)
		(duplicate_pad_numbers_are_jumpers no)
		(fp_poly
			(pts
				(xy 0.7239 -0.2159) (xy -0.7239 -0.2159) (xy -0.7239 1.9939) (xy 0.7239 1.9939)
			)
			(stroke
				(width 0)
				(type default)
			)
			(fill no)
			(layer "B.CrtYd")
		)
		(fp_line
			(start 0.7239 -0.2159)
			(end 0.7239 1.9939)
			(stroke
				(width 0.1)
				(type default)
			)
			(layer "B.Fab")
		)
		(fp_line
			(start -0.7239 -0.2159)
			(end 0.7239 -0.2159)
			(stroke
				(width 0.1)
				(type default)
			)
			(layer "B.Fab")
		)
		(fp_line
			(start 0.7239 1.9939)
			(end -0.7239 1.9939)
			(stroke
				(width 0.1)
				(type default)
			)
			(layer "B.Fab")
		)
		(fp_line
			(start -0.7239 1.9939)
			(end -0.7239 -0.2159)
			(stroke
				(width 0.1)
				(type default)
			)
			(layer "B.Fab")
		)
		(pad "1" smd rect
			(at 0 0 270)
			(size 1.27 1.016)
			(layers "B.Cu" "B.Mask" "B.Paste")
			(net "VR_FET_SW_P12V_STBY_PVCCIN_CPU1")
		)
		(pad "2" smd rect
			(at 0 1.778 270)
			(size 1.27 1.016)
			(layers "B.Cu" "B.Mask" "B.Paste")
			(net "GND")
		)
		(zone
			(layer "B.Cu")
			(hatch none 0.5)
			(connect_pads
				(clearance 0)
			)
			(min_thickness 0.25)
			(keepout
				(tracks not_allowed)
				(vias allowed)
				(pads allowed)
				(copperpour not_allowed)
				(footprints allowed)
			)
			(placement
				(enabled no)
				(sheetname "")
			)
			(fill
				(thermal_gap 0.5)
				(thermal_bridge_width 0.5)
				(island_removal_mode 0)
			)
			(polygon
				(pts
					(xy 33.340802 -97.921064) (xy 33.340802 -96.651064) (xy 34.102802 -96.651064) (xy 34.102802 -97.921064)
				)
			)
		)
	)
	(footprint ""
		(layer "B.Cu")
		(at 481.623116 -143.247872 90)
		(property "Reference" "R6W7"
			(at 0.8382 -0.67818 90)
			(unlocked yes)
			(layer "B.SilkS")
			(effects
				(font
					(size 0.4064 0.254)
					(thickness 0.1524)
				)
				(justify left mirror)
			)
		)
		(property "Value" ""
			(at 0 0 90)
			(layer "B.Fab")
			(effects
				(font
					(size 1.27 1.27)
				)
				(justify mirror)
			)
		)
		(duplicate_pad_numbers_are_jumpers no)
		(fp_poly
			(pts
				(xy 0.2794 -0.1016) (xy -0.2794 -0.1016) (xy -0.2794 0.9906) (xy 0.2794 0.9906)
			)
			(stroke
				(width 0)
				(type default)
			)
			(fill no)
			(layer "B.CrtYd")
		)
		(fp_line
			(start 0.2794 -0.1016)
			(end 0.2794 0.9906)
			(stroke
				(width 0.1)
				(type default)
			)
			(layer "B.Fab")
		)
		(fp_line
			(start -0.2794 -0.1016)
			(end 0.2794 -0.1016)
			(stroke
				(width 0.1)
				(type default)
			)
			(layer "B.Fab")
		)
		(fp_line
			(start 0.2794 0.9906)
			(end -0.2794 0.9906)
			(stroke
				(width 0.1)
				(type default)
			)
			(layer "B.Fab")
		)
		(fp_line
			(start -0.2794 0.9906)
			(end -0.2794 -0.1016)
			(stroke
				(width 0.1)
				(type default)
			)
			(layer "B.Fab")
		)
		(pad "1" smd rect
			(at 0 0 270)
			(size 0.508 0.508)
			(layers "B.Cu" "B.Mask" "B.Paste")
			(net "PCA9555_A2")
		)
		(pad "2" smd rect
			(at 0 0.889 270)
			(size 0.508 0.508)
			(layers "B.Cu" "B.Mask" "B.Paste")
			(net "GND")
		)
		(zone
			(layer "B.Cu")
			(hatch none 0.5)
			(connect_pads
				(clearance 0)
			)
			(min_thickness 0.25)
			(keepout
				(tracks allowed)
				(vias not_allowed)
				(pads allowed)
				(copperpour not_allowed)
				(footprints allowed)
			)
			(placement
				(enabled no)
				(sheetname "")
			)
			(fill
				(thermal_gap 0.5)
				(thermal_bridge_width 0.5)
				(island_removal_mode 0)
			)
			(polygon
				(pts
					(xy 481.877116 -143.501872) (xy 481.877116 -142.993872) (xy 482.258116 -142.993872) (xy 482.258116 -143.501872)
				)
			)
		)
		(zone
			(layer "B.Cu")
			(hatch none 0.5)
			(connect_pads
				(clearance 0)
			)
			(min_thickness 0.25)
			(keepout
				(tracks not_allowed)
				(vias allowed)
				(pads allowed)
				(copperpour not_allowed)
				(footprints allowed)
			)
			(placement
				(enabled no)
				(sheetname "")
			)
			(fill
				(thermal_gap 0.5)
				(thermal_bridge_width 0.5)
				(island_removal_mode 0)
			)
			(polygon
				(pts
					(xy 482.258116 -143.501872) (xy 482.258116 -142.993872) (xy 481.877116 -142.993872) (xy 481.877116 -143.501872)
				)
			)
		)
	)
	(footprint ""
		(layer "B.Cu")
		(at 275.008086 -73.51014)
		(property "Reference" "C5P28"
			(at 0 0 0)
			(layer "B.SilkS")
			(hide yes)
			(effects
				(font
					(size 1.27 1.27)
				)
				(justify mirror)
			)
		)
		(property "Value" ""
			(at 0 0 0)
			(layer "B.Fab")
			(effects
				(font
					(size 1.27 1.27)
				)
				(justify mirror)
			)
		)
		(duplicate_pad_numbers_are_jumpers no)
		(fp_poly
			(pts
				(xy 0.7239 -0.2159) (xy -0.7239 -0.2159) (xy -0.7239 1.9939) (xy 0.7239 1.9939)
			)
			(stroke
				(width 0)
				(type default)
			)
			(fill no)
			(layer "B.CrtYd")
		)
		(fp_line
			(start -0.7239 -0.2159)
			(end 0.7239 -0.2159)
			(stroke
				(width 0.1)
				(type default)
			)
			(layer "B.Fab")
		)
		(fp_line
			(start -0.7239 1.9939)
			(end -0.7239 -0.2159)
			(stroke
				(width 0.1)
				(type default)
			)
			(layer "B.Fab")
		)
		(fp_line
			(start 0.7239 -0.2159)
			(end 0.7239 1.9939)
			(stroke
				(width 0.1)
				(type default)
			)
			(layer "B.Fab")
		)
		(fp_line
			(start 0.7239 1.9939)
			(end -0.7239 1.9939)
			(stroke
				(width 0.1)
				(type default)
			)
			(layer "B.Fab")
		)
		(pad "1" smd rect
			(at 0 0 180)
			(size 1.27 1.016)
			(layers "B.Cu" "B.Mask" "B.Paste")
			(net "PVCCMCP_CPU0")
		)
		(pad "2" smd rect
			(at 0 1.778 180)
			(size 1.27 1.016)
			(layers "B.Cu" "B.Mask" "B.Paste")
			(net "GND")
		)
		(zone
			(layer "B.Cu")
			(hatch none 0.5)
			(connect_pads
				(clearance 0)
			)
			(min_thickness 0.25)
			(keepout
				(tracks not_allowed)
				(vias allowed)
				(pads allowed)
				(copperpour not_allowed)
				(footprints allowed)
			)
			(placement
				(enabled no)
				(sheetname "")
			)
			(fill
				(thermal_gap 0.5)
				(thermal_bridge_width 0.5)
				(island_removal_mode 0)
			)
			(polygon
				(pts
					(xy 275.643086 -73.00214) (xy 274.373086 -73.00214) (xy 274.373086 -72.24014) (xy 275.643086 -72.24014)
				)
			)
		)
	)
	(footprint ""
		(layer "B.Cu")
		(at 13.11402 -97.99828 90)
		(property "Reference" "C9N17"
			(at 0 0 90)
			(layer "B.SilkS")
			(hide yes)
			(effects
				(font
					(size 1.27 1.27)
				)
				(justify mirror)
			)
		)
		(property "Value" ""
			(at 0 0 90)
			(layer "B.Fab")
			(effects
				(font
					(size 1.27 1.27)
				)
				(justify mirror)
			)
		)
		(duplicate_pad_numbers_are_jumpers no)
		(fp_poly
			(pts
				(xy -0.3048 -0.1016) (xy -0.3048 0.9906) (xy 0.3048 0.9906) (xy 0.3048 -0.1016)
			)
			(stroke
				(width 0)
				(type default)
			)
			(fill no)
			(layer "B.CrtYd")
		)
		(fp_line
			(start 0.3048 -0.1016)
			(end 0.3048 0.9906)
			(stroke
				(width 0.1)
				(type default)
			)
			(layer "B.Fab")
		)
		(fp_line
			(start -0.3048 -0.1016)
			(end 0.3048 -0.1016)
			(stroke
				(width 0.1)
				(type default)
			)
			(layer "B.Fab")
		)
		(fp_line
			(start 0.3048 0.9906)
			(end -0.3048 0.9906)
			(stroke
				(width 0.1)
				(type default)
			)
			(layer "B.Fab")
		)
		(fp_line
			(start -0.3048 0.9906)
			(end -0.3048 -0.1016)
			(stroke
				(width 0.1)
				(type default)
			)
			(layer "B.Fab")
		)
		(pad "1" smd rect
			(at 0 0 270)
			(size 0.508 0.508)
			(layers "B.Cu" "B.Mask" "B.Paste")
			(net "P3E_CPU1_PE3_MP_C_TXP<8>")
		)
		(pad "2" smd rect
			(at 0 0.889 270)
			(size 0.508 0.508)
			(layers "B.Cu" "B.Mask" "B.Paste")
			(net "P3E_CPU1_PE3_MP_TXP<8>")
		)
		(zone
			(layer "B.Cu")
			(hatch none 0.5)
			(connect_pads
				(clearance 0)
			)
			(min_thickness 0.25)
			(keepout
				(tracks allowed)
				(vias not_allowed)
				(pads allowed)
				(copperpour not_allowed)
				(footprints allowed)
			)
			(placement
				(enabled no)
				(sheetname "")
			)
			(fill
				(thermal_gap 0.5)
				(thermal_bridge_width 0.5)
				(island_removal_mode 0)
			)
			(polygon
				(pts
					(xy 13.36802 -98.25228) (xy 13.36802 -97.74428) (xy 13.74902 -97.74428) (xy 13.74902 -98.25228)
				)
			)
		)
		(zone
			(layer "B.Cu")
			(hatch none 0.5)
			(connect_pads
				(clearance 0)
			)
			(min_thickness 0.25)
			(keepout
				(tracks not_allowed)
				(vias allowed)
				(pads allowed)
				(copperpour not_allowed)
				(footprints allowed)
			)
			(placement
				(enabled no)
				(sheetname "")
			)
			(fill
				(thermal_gap 0.5)
				(thermal_bridge_width 0.5)
				(island_removal_mode 0)
			)
			(polygon
				(pts
					(xy 13.74902 -98.25228) (xy 13.74902 -97.74428) (xy 13.36802 -97.74428) (xy 13.36802 -98.25228)
				)
			)
		)
	)
	(footprint ""
		(layer "B.Cu")
		(at 439.976006 -41.648126 180)
		(property "Reference" "R25W15"
			(at 0 0 0)
			(layer "B.SilkS")
			(hide yes)
			(effects
				(font
					(size 1.27 1.27)
				)
				(justify mirror)
			)
		)
		(property "Value" "*"
			(at -0.064008 -4.108196 180)
			(unlocked yes)
			(layer "B.Fab")
			(hide yes)
			(effects
				(font
					(size 1.27 1.016)
					(thickness 0.1524)
				)
				(justify mirror)
			)
		)
		(property "Device Type" "120R2F-GP_RCL_GP-120R2F-GP,64.A"
			(at -0.064008 -5.632196 180)
			(unlocked yes)
			(layer "B.Fab")
			(hide yes)
			(effects
				(font
					(size 1.27 1.016)
					(thickness 0.1524)
				)
				(justify mirror)
			)
		)
		(duplicate_pad_numbers_are_jumpers no)
		(fp_line
			(start 0.508 -0.9398)
			(end 0.508 0.9398)
			(stroke
				(width 0.1524)
				(type default)
			)
			(layer "B.SilkS")
		)
		(fp_line
			(start -0.508 -0.9398)
			(end 0.508 -0.9398)
			(stroke
				(width 0.1524)
				(type default)
			)
			(layer "B.SilkS")
		)
		(fp_rect
			(start 0.508 0.9398)
			(end -0.508 -0.9398)
			(stroke
				(width 0)
				(type default)
			)
			(fill no)
			(layer "B.CrtYd")
		)
		(fp_rect
			(start 0.508 0.9398)
			(end -0.508 -0.9398)
			(stroke
				(width 0)
				(type default)
			)
			(fill no)
			(layer "B.Fab")
		)
		(pad "1" smd custom
			(at 0 -0.4445)
			(size 0.1397 0.1397)
			(layers "B.Cu" "B.Mask" "B.Paste")
			(net "GND")
			(options
				(clearance outline)
				(anchor circle)
			)
			(primitives
				(gr_poly
					(pts
						(arc
							(start -0.1778 0.2794)
							(mid -0.249642 0.249642)
							(end -0.2794 0.1778)
						)
						(arc
							(start -0.2794 -0.1778)
							(mid -0.249642 -0.249642)
							(end -0.1778 -0.2794)
						)
						(arc
							(start 0.1778 -0.2794)
							(mid 0.249642 -0.249642)
							(end 0.2794 -0.1778)
						)
						(arc
							(start 0.2794 0.1778)
							(mid 0.249642 0.249642)
							(end 0.1778 0.2794)
						)
					)
					(width 0)
					(fill yes)
				)
			)
		)
		(pad "2" smd custom
			(at 0 0.4445)
			(size 0.1397 0.1397)
			(layers "B.Cu" "B.Mask" "B.Paste")
			(net "BMC_M_A3")
			(options
				(clearance outline)
				(anchor circle)
			)
			(primitives
				(gr_poly
					(pts
						(arc
							(start -0.1778 0.2794)
							(mid -0.249642 0.249642)
							(end -0.2794 0.1778)
						)
						(arc
							(start -0.2794 -0.1778)
							(mid -0.249642 -0.249642)
							(end -0.1778 -0.2794)
						)
						(arc
							(start 0.1778 -0.2794)
							(mid 0.249642 -0.249642)
							(end 0.2794 -0.1778)
						)
						(arc
							(start 0.2794 0.1778)
							(mid 0.249642 0.249642)
							(end 0.1778 0.2794)
						)
					)
					(width 0)
					(fill yes)
				)
			)
		)
	)
	(footprint ""
		(layer "B.Cu")
		(at 346.814902 -133.133846 180)
		(property "Reference" "C3M15"
			(at 0 0 0)
			(layer "B.SilkS")
			(hide yes)
			(effects
				(font
					(size 1.27 1.27)
				)
				(justify mirror)
			)
		)
		(property "Value" ""
			(at 0 0 0)
			(layer "B.Fab")
			(effects
				(font
					(size 1.27 1.27)
				)
				(justify mirror)
			)
		)
		(duplicate_pad_numbers_are_jumpers no)
		(fp_poly
			(pts
				(xy 0.7239 -0.2159) (xy -0.7239 -0.2159) (xy -0.7239 1.9939) (xy 0.7239 1.9939)
			)
			(stroke
				(width 0)
				(type default)
			)
			(fill no)
			(layer "B.CrtYd")
		)
		(fp_line
			(start 0.7239 1.9939)
			(end -0.7239 1.9939)
			(stroke
				(width 0.1)
				(type default)
			)
			(layer "B.Fab")
		)
		(fp_line
			(start 0.7239 -0.2159)
			(end 0.7239 1.9939)
			(stroke
				(width 0.1)
				(type default)
			)
			(layer "B.Fab")
		)
		(fp_line
			(start -0.7239 1.9939)
			(end -0.7239 -0.2159)
			(stroke
				(width 0.1)
				(type default)
			)
			(layer "B.Fab")
		)
		(fp_line
			(start -0.7239 -0.2159)
			(end 0.7239 -0.2159)
			(stroke
				(width 0.1)
				(type default)
			)
			(layer "B.Fab")
		)
		(pad "1" smd rect
			(at 0 0)
			(size 1.27 1.016)
			(layers "B.Cu" "B.Mask" "B.Paste")
			(net "VR_FET_SW_P12V_STBY_PVPP_DEF")
		)
		(pad "2" smd rect
			(at 0 1.778)
			(size 1.27 1.016)
			(layers "B.Cu" "B.Mask" "B.Paste")
			(net "GND")
		)
		(zone
			(layer "B.Cu")
			(hatch none 0.5)
			(connect_pads
				(clearance 0)
			)
			(min_thickness 0.25)
			(keepout
				(tracks not_allowed)
				(vias allowed)
				(pads allowed)
				(copperpour not_allowed)
				(footprints allowed)
			)
			(placement
				(enabled no)
				(sheetname "")
			)
			(fill
				(thermal_gap 0.5)
				(thermal_bridge_width 0.5)
				(island_removal_mode 0)
			)
			(polygon
				(pts
					(xy 346.179902 -133.641846) (xy 347.449902 -133.641846) (xy 347.449902 -134.403846) (xy 346.179902 -134.403846)
				)
			)
		)
	)
	(footprint ""
		(layer "B.Cu")
		(at 108.178854 -73.51014)
		(property "Reference" "C7P15"
			(at 0 0 0)
			(layer "B.SilkS")
			(hide yes)
			(effects
				(font
					(size 1.27 1.27)
				)
				(justify mirror)
			)
		)
		(property "Value" ""
			(at 0 0 0)
			(layer "B.Fab")
			(effects
				(font
					(size 1.27 1.27)
				)
				(justify mirror)
			)
		)
		(duplicate_pad_numbers_are_jumpers no)
		(fp_poly
			(pts
				(xy 0.7239 -0.2159) (xy -0.7239 -0.2159) (xy -0.7239 1.9939) (xy 0.7239 1.9939)
			)
			(stroke
				(width 0)
				(type default)
			)
			(fill no)
			(layer "B.CrtYd")
		)
		(fp_line
			(start -0.7239 -0.2159)
			(end 0.7239 -0.2159)
			(stroke
				(width 0.1)
				(type default)
			)
			(layer "B.Fab")
		)
		(fp_line
			(start -0.7239 1.9939)
			(end -0.7239 -0.2159)
			(stroke
				(width 0.1)
				(type default)
			)
			(layer "B.Fab")
		)
		(fp_line
			(start 0.7239 -0.2159)
			(end 0.7239 1.9939)
			(stroke
				(width 0.1)
				(type default)
			)
			(layer "B.Fab")
		)
		(fp_line
			(start 0.7239 1.9939)
			(end -0.7239 1.9939)
			(stroke
				(width 0.1)
				(type default)
			)
			(layer "B.Fab")
		)
		(pad "1" smd rect
			(at 0 0 180)
			(size 1.27 1.016)
			(layers "B.Cu" "B.Mask" "B.Paste")
			(net "PVCCMCP_CPU1")
		)
		(pad "2" smd rect
			(at 0 1.778 180)
			(size 1.27 1.016)
			(layers "B.Cu" "B.Mask" "B.Paste")
			(net "GND")
		)
		(zone
			(layer "B.Cu")
			(hatch none 0.5)
			(connect_pads
				(clearance 0)
			)
			(min_thickness 0.25)
			(keepout
				(tracks not_allowed)
				(vias allowed)
				(pads allowed)
				(copperpour not_allowed)
				(footprints allowed)
			)
			(placement
				(enabled no)
				(sheetname "")
			)
			(fill
				(thermal_gap 0.5)
				(thermal_bridge_width 0.5)
				(island_removal_mode 0)
			)
			(polygon
				(pts
					(xy 108.813854 -73.00214) (xy 107.543854 -73.00214) (xy 107.543854 -72.24014) (xy 108.813854 -72.24014)
				)
			)
		)
	)
)
